<schema xmlns="http://www.cadence.com/spb/csschema"
	xmlns:xsi="http://www.w3.org/2001/XMLSchema-instance"
	xsi:schemaLocation="http://www.cadence.com/spb/csschema CSSchema002.xsd">
  <header>
    <schemaVersion>16.5</schemaVersion>
    <creatorTool>conceptHDL</creatorTool>
    <modifierTool>conceptHDL</modifierTool>
    <modificationTime>2011-10-25T13:21:18</modificationTime>
    <savedLibrary>mstr_symbols</savedLibrary>
  </header>
  <designs>
    <design schemaType="nameBased" name="p12v_stby" view="sch_1">
      <lastids>
        <netid>4</netid>
      </lastids>
      <cells>
      </cells>
      <nets>
        <net>
          <id>N1</id>
          <name>g</name>
          <scope>interface</scope>
          <direction>inout</direction>
        </net>
        <net>
          <id>N2</id>
          <name>page1_g</name>
        </net>
        <net>
          <id>N4</id>
          <name>page1_p12v_stby</name>
        </net>
        <net>
          <id>N3</id>
          <name>p12v_stby</name>
          <scope>global</scope>
        </net>
      </nets>
      <aliases>
        <alias net1="N2" lsb1="-1" msb1="-1" net2="N1" lsb2="-1" msb2="-1" />
        <alias net1="N4" lsb1="-1" msb1="-1" net2="N2" lsb2="-1" msb2="-1" />
        <alias net1="N4" lsb1="-1" msb1="-1" net2="N3" lsb2="-1" msb2="-1" />
      </aliases>
      <differentialnets>
      </differentialnets>
      <differentialbusnets>
      </differentialbusnets>
      <netgroups>
      </netgroups>
      <netinterfaces>
      </netinterfaces>
      <instances>
      </instances>
      <templateresolutions>
      </templateresolutions>
      <templateinstances>
      </templateinstances>
      <extensions>
        <extension name="schematic_extension">
        <schematicExtension>
        <errorStatus>true</errorStatus>
        <netScopes>
          <netScope ref="g">
            <pageScope number="1">
              <scope>interface</scope>
              <direction>unknown</direction>
            </pageScope>
          </netScope>
          <netScope ref="p12v_stby">
            <pageScope number="1">
              <scope>global</scope>
            </pageScope>
          </netScope>
        </netScopes>
        <pages>
          <page number="1">
            <physicalPageNumber>1</physicalPageNumber>
            <errorStatus>false</errorStatus>
            <nets>
              <net ref="g"></net>
              <net ref="p12v_stby"></net>
            </nets>
            <instances>
            </instances>
          </page>
        </pages>
      </schematicExtension>
        </extension>
      </extensions>
    </design>
  </designs>
</schema>
